# T6G (Grand Teton) — schematic netlist excerpt (pin names and nets, part order shuffled) for the footprints in the layout excerpt that follows; sources: Cadence DE-HDL packaged netlist, KiCad conversion of 04192023_DAF0TMB3IC0_F0TG_MB_C_brd_V02_OCP.brd

H27  HOLE  EMPTY  pkg TH  page 230 : \1\ = NC
R2411  Q_RES  33.2 1% CHIP  pkg 0402LF  page 148 : A = SMB_M2_P1_1V8AUX_SCL_R ; B = SMB_M2_P1_1V8AUX_SCL

(kicad_pcb
	(version 20260206)
	(generator "pcbnew")
	(generator_version "10.0")
	(general
		(thickness 1.6)
		(legacy_teardrops no)
	)
	(paper "A4")
	(title_block
		(title "04192023_DAF0TMB3IC0_F0TG_MB_C_brd_V02_OCP.brd")
		(comment 1 "Grand Teton / footprints 291-292 of 8354")
	)
	(layers
		(0 "F.Cu" signal "TOP")
		(4 "In1.Cu" signal "GND")
		(6 "In2.Cu" signal "IN1")
		(8 "In3.Cu" signal "GND1")
		(10 "In4.Cu" signal "IN2")
		(12 "In5.Cu" signal "GND2")
		(14 "In6.Cu" signal "IN3")
		(16 "In7.Cu" signal "GND3")
		(18 "In8.Cu" signal "VCC")
		(20 "In9.Cu" signal "VCC1")
		(22 "In10.Cu" signal "GND4")
		(24 "In11.Cu" signal "IN4")
		(26 "In12.Cu" signal "GND5")
		(28 "In13.Cu" signal "IN5")
		(30 "In14.Cu" signal "GND6")
		(32 "In15.Cu" signal "IN6")
		(34 "In16.Cu" signal "GND7")
		(2 "B.Cu" signal "BOTTOM")
		(9 "F.Adhes" user "F.Adhesive")
		(11 "B.Adhes" user "B.Adhesive")
		(13 "F.Paste" user "Package Geometry/Pastemask Top")
		(15 "B.Paste" user "Package Geometry/Pastemask Bottom")
		(5 "F.SilkS" user "Ref Des/Silkscreen Top")
		(7 "B.SilkS" user "Ref Des/Silkscreen Bottom")
		(1 "F.Mask" user "Board Geometry/Soldermask Top")
		(3 "B.Mask" user "Board Geometry/Soldermask Bottom")
		(17 "Dwgs.User" user "User.Drawings")
		(19 "Cmts.User" user "User.Comments")
		(21 "Eco1.User" user "User.Eco1")
		(23 "Eco2.User" user "User.Eco2")
		(25 "Edge.Cuts" user "Board Geometry/Outline")
		(27 "Margin" user)
		(31 "F.CrtYd" user "Package Geometry/Place Bound Top")
		(29 "B.CrtYd" user "Package Geometry/Place Bound Bottom")
		(35 "F.Fab" user "Ref Des/Assembly Top")
		(33 "B.Fab" user "Ref Des/Assembly Bottom")
	)
	(footprint ""
		(layer "F.Cu")
		(at 146.304762 -43.03141 180)
		(property "Reference" "R2411"
			(at 0 0 180)
			(layer "F.SilkS")
			(hide yes)
			(effects
				(font
					(size 1.27 1.27)
				)
			)
		)
		(property "Value" ""
			(at 0 0 180)
			(layer "F.Fab")
			(effects
				(font
					(size 1.27 1.27)
				)
			)
		)
		(duplicate_pad_numbers_are_jumpers no)
		(fp_line
			(start 0.7874 0.4064)
			(end -0.7874 0.4064)
			(stroke
				(width 0.1524)
				(type default)
			)
			(layer "F.SilkS")
		)
		(fp_line
			(start 0.7874 -0.4064)
			(end 0.7874 0.4064)
			(stroke
				(width 0.1524)
				(type default)
			)
			(layer "F.SilkS")
		)
		(fp_line
			(start -0.7874 0.4064)
			(end -0.7874 -0.4064)
			(stroke
				(width 0.1524)
				(type default)
			)
			(layer "F.SilkS")
		)
		(fp_line
			(start -0.7874 -0.4064)
			(end 0.7874 -0.4064)
			(stroke
				(width 0.1524)
				(type default)
			)
			(layer "F.SilkS")
		)
		(fp_line
			(start 0.67945 0.3048)
			(end 0.120396 0.3048)
			(stroke
				(width 0.1)
				(type default)
			)
			(layer "F.Fab")
		)
		(fp_line
			(start 0.67945 -0.3048)
			(end 0.67945 0.3048)
			(stroke
				(width 0.1)
				(type default)
			)
			(layer "F.Fab")
		)
		(fp_line
			(start 0.12065 -0.2794)
			(end 0.12065 -0.3048)
			(stroke
				(width 0.1)
				(type default)
			)
			(layer "F.Fab")
		)
		(fp_line
			(start 0.12065 -0.3048)
			(end 0.67945 -0.3048)
			(stroke
				(width 0.1)
				(type default)
			)
			(layer "F.Fab")
		)
		(fp_line
			(start 0.120396 0.3048)
			(end 0.120396 0.2794)
			(stroke
				(width 0.1)
				(type default)
			)
			(layer "F.Fab")
		)
		(fp_line
			(start 0.120396 0.2794)
			(end -0.12065 0.2794)
			(stroke
				(width 0.1)
				(type default)
			)
			(layer "F.Fab")
		)
		(fp_line
			(start -0.12065 0.3048)
			(end -0.67945 0.3048)
			(stroke
				(width 0.1)
				(type default)
			)
			(layer "F.Fab")
		)
		(fp_line
			(start -0.12065 0.2794)
			(end -0.12065 0.3048)
			(stroke
				(width 0.1)
				(type default)
			)
			(layer "F.Fab")
		)
		(fp_line
			(start -0.12065 -0.2794)
			(end 0.12065 -0.2794)
			(stroke
				(width 0.1)
				(type default)
			)
			(layer "F.Fab")
		)
		(fp_line
			(start -0.12065 -0.305054)
			(end -0.12065 -0.2794)
			(stroke
				(width 0.1)
				(type default)
			)
			(layer "F.Fab")
		)
		(fp_line
			(start -0.67945 0.3048)
			(end -0.67945 -0.305054)
			(stroke
				(width 0.1)
				(type default)
			)
			(layer "F.Fab")
		)
		(fp_line
			(start -0.67945 -0.305054)
			(end -0.12065 -0.305054)
			(stroke
				(width 0.1)
				(type default)
			)
			(layer "F.Fab")
		)
		(pad "1" smd circle
			(at -0.40005 0 180)
			(size 0 0)
			(layers "F.Cu" "F.Mask" "F.Paste")
			(net "SMB_M2_P1_1V8AUX_SCL_R")
		)
		(pad "2" smd circle
			(at 0.40005 0 180)
			(size 0 0)
			(layers "F.Cu" "F.Mask" "F.Paste")
			(net "SMB_M2_P1_1V8AUX_SCL")
		)
	)
	(footprint ""
		(layer "F.Cu")
		(at 458.3811 -423.492168)
		(property "Reference" "H27"
			(at 2.5654 2.321052 0)
			(unlocked yes)
			(layer "F.SilkS")
			(effects
				(font
					(size 0.7874 0.5842)
					(thickness 0.1524)
				)
				(justify left)
			)
		)
		(property "Value" ""
			(at 0 0 0)
			(layer "F.Fab")
			(effects
				(font
					(size 1.27 1.27)
				)
			)
		)
		(duplicate_pad_numbers_are_jumpers no)
		(fp_circle
			(center 0 0)
			(end 2.4003 0)
			(stroke
				(width 0.1524)
				(type default)
			)
			(fill no)
			(layer "F.SilkS")
		)
		(fp_circle
			(center 0 0)
			(end 6.5913 0)
			(stroke
				(width 0.1524)
				(type default)
			)
			(fill no)
			(layer "B.SilkS")
		)
		(fp_circle
			(center 0 0)
			(end 6.5913 0)
			(stroke
				(width 0.1)
				(type default)
			)
			(fill no)
			(layer "B.Fab")
		)
		(fp_circle
			(center 0 0)
			(end 2.4003 0)
			(stroke
				(width 0.1)
				(type default)
			)
			(fill no)
			(layer "F.Fab")
		)
		(pad "" np_thru_hole circle
			(at 0 0)
			(size 3.175 3.175)
			(drill 3.175)
			(layers "*.Cu" "*.Mask")
			(clearance 0.381)
			(thermal_gap 0.381)
		)
		(zone
			(layers "F.Cu" "B.Cu" "In1.Cu" "In2.Cu" "In3.Cu" "In4.Cu" "In5.Cu" "In6.Cu"
				"In7.Cu" "In8.Cu" "In9.Cu" "In10.Cu" "In11.Cu" "In12.Cu" "In13.Cu" "In14.Cu"
				"In15.Cu" "In16.Cu"
			)
			(hatch none 0.5)
			(connect_pads
				(clearance 0)
			)
			(min_thickness 0.25)
			(keepout
				(tracks not_allowed)
				(vias allowed)
				(pads allowed)
				(copperpour not_allowed)
				(footprints allowed)
			)
			(placement
				(enabled no)
				(sheetname "")
			)
			(fill
				(thermal_gap 0.5)
				(thermal_bridge_width 0.5)
				(island_removal_mode 0)
			)
			(polygon
				(pts
					(arc
						(start 460.4766 -423.492168)
						(mid 456.2856 -423.492168)
						(end 460.4766 -423.492168)
					)
				)
			)
		)
	)
)
